# BASEBOARD_FAB2 (Tioga Pass) — schematic netlist excerpt (pin names and nets, part order shuffled) for the footprints in the layout excerpt that follows; sources: Cadence DE-HDL packaged netlist, KiCad conversion of Wiwynn_Tioga_Pass_MB.brd

C5L7  CAP_A  47UF 4V 20% X5R  pkg 0603V  page 220 : A = PVDDQ_DEF ; B = GND
C3P26  CAP  0.22UF 16V 10% X7R  pkg 0402  page 107 : A = P3E_CPU0_PE1_SS_TXP<4> ; B = P3E_CPU0_PE1_SS_C_TXP<4>
R7P2  RES  42.2 1.0% EMPTY  pkg 0402  page 103 : A = CLK_100M_CPU1_BCLK2_DN ; B = GND

(kicad_pcb
	(version 20260206)
	(generator "pcbnew")
	(generator_version "10.0")
	(general
		(thickness 1.6)
		(legacy_teardrops no)
	)
	(paper "A4")
	(title_block
		(title "Wiwynn_Tioga_Pass_MB.brd")
		(comment 1 "Tioga Pass / footprints 4145-4147 of 4770")
	)
	(layers
		(0 "F.Cu" signal "TOP")
		(4 "In1.Cu" signal "L2GND")
		(6 "In2.Cu" signal "L3")
		(8 "In3.Cu" signal "L4GND")
		(10 "In4.Cu" signal "L5")
		(12 "In5.Cu" signal "L6GND")
		(14 "In6.Cu" signal "L7VCC")
		(16 "In7.Cu" signal "L8VCC")
		(18 "In8.Cu" signal "L9GND")
		(20 "In9.Cu" signal "L10")
		(22 "In10.Cu" signal "L11GND")
		(24 "In11.Cu" signal "L12")
		(26 "In12.Cu" signal "L13GND")
		(2 "B.Cu" signal "BOTTOM")
		(9 "F.Adhes" user "F.Adhesive")
		(11 "B.Adhes" user "B.Adhesive")
		(13 "F.Paste" user "Package Geometry/Pastemask Top")
		(15 "B.Paste" user "Package Geometry/Pastemask Bottom")
		(5 "F.SilkS" user "Ref Des/Silkscreen Top")
		(7 "B.SilkS" user "Ref Des/Silkscreen Bottom")
		(1 "F.Mask" user "Board Geometry/Soldermask Top")
		(3 "B.Mask" user "Board Geometry/Soldermask Bottom")
		(17 "Dwgs.User" user "User.Drawings")
		(19 "Cmts.User" user "User.Comments")
		(21 "Eco1.User" user "User.Eco1")
		(23 "Eco2.User" user "User.Eco2")
		(25 "Edge.Cuts" user "Board Geometry/Outline")
		(27 "Margin" user)
		(31 "F.CrtYd" user "Package Geometry/Place Bound Top")
		(29 "B.CrtYd" user "Package Geometry/Place Bound Bottom")
		(35 "F.Fab" user "Ref Des/Assembly Top")
		(33 "B.Fab" user "Ref Des/Assembly Bottom")
	)
	(footprint ""
		(layer "B.Cu")
		(at 272.861532 -145.0086 90)
		(property "Reference" "C5L7"
			(at -1.848866 0.752348 90)
			(unlocked yes)
			(layer "B.SilkS")
			(effects
				(font
					(size 1.27 0.9652)
					(thickness 0.1524)
				)
				(justify mirror)
			)
		)
		(property "Value" ""
			(at 0 0 90)
			(layer "B.Fab")
			(effects
				(font
					(size 1.27 1.27)
				)
				(justify mirror)
			)
		)
		(duplicate_pad_numbers_are_jumpers no)
		(fp_rect
			(start 0.500126 1.598422)
			(end -0.500126 -0.201422)
			(stroke
				(width 0)
				(type default)
			)
			(fill no)
			(layer "B.CrtYd")
		)
		(fp_line
			(start 0.500126 -0.201422)
			(end -0.500126 -0.201422)
			(stroke
				(width 0.1)
				(type default)
			)
			(layer "B.Fab")
		)
		(fp_line
			(start -0.500126 -0.201422)
			(end -0.500126 1.598422)
			(stroke
				(width 0.1)
				(type default)
			)
			(layer "B.Fab")
		)
		(fp_line
			(start 0.500126 1.598422)
			(end 0.500126 -0.201422)
			(stroke
				(width 0.1)
				(type default)
			)
			(layer "B.Fab")
		)
		(fp_line
			(start -0.500126 1.598422)
			(end 0.500126 1.598422)
			(stroke
				(width 0.1)
				(type default)
			)
			(layer "B.Fab")
		)
		(pad "1" smd rect
			(at 0 0)
			(size 0.889 0.9906)
			(layers "B.Cu" "B.Mask" "B.Paste")
			(net "PVDDQ_DEF")
		)
		(pad "2" smd rect
			(at 0 1.397)
			(size 0.889 0.9906)
			(layers "B.Cu" "B.Mask" "B.Paste")
			(net "GND")
		)
		(zone
			(layer "B.Cu")
			(hatch none 0.5)
			(connect_pads
				(clearance 0)
			)
			(min_thickness 0.25)
			(keepout
				(tracks not_allowed)
				(vias allowed)
				(pads allowed)
				(copperpour not_allowed)
				(footprints allowed)
			)
			(placement
				(enabled no)
				(sheetname "")
			)
			(fill
				(thermal_gap 0.5)
				(thermal_bridge_width 0.5)
				(island_removal_mode 0)
			)
			(polygon
				(pts
					(xy 273.814032 -145.5039) (xy 273.306032 -145.5039) (xy 273.306032 -144.5133) (xy 273.814032 -144.5133)
				)
			)
		)
		(zone
			(layer "B.Cu")
			(hatch none 0.5)
			(connect_pads
				(clearance 0)
			)
			(min_thickness 0.25)
			(keepout
				(tracks allowed)
				(vias not_allowed)
				(pads allowed)
				(copperpour not_allowed)
				(footprints allowed)
			)
			(placement
				(enabled no)
				(sheetname "")
			)
			(fill
				(thermal_gap 0.5)
				(thermal_bridge_width 0.5)
				(island_removal_mode 0)
			)
			(polygon
				(pts
					(xy 273.814032 -145.5039) (xy 273.306032 -145.5039) (xy 273.306032 -144.5133) (xy 273.814032 -144.5133)
				)
			)
		)
	)
	(footprint ""
		(layer "B.Cu")
		(at 162.91306 -84.328 90)
		(property "Reference" "R7P2"
			(at 0 0 90)
			(layer "B.SilkS")
			(hide yes)
			(effects
				(font
					(size 1.27 1.27)
				)
				(justify mirror)
			)
		)
		(property "Value" ""
			(at 0 0 90)
			(layer "B.Fab")
			(effects
				(font
					(size 1.27 1.27)
				)
				(justify mirror)
			)
		)
		(duplicate_pad_numbers_are_jumpers no)
		(fp_poly
			(pts
				(xy 0.2794 -0.1016) (xy -0.2794 -0.1016) (xy -0.2794 0.9906) (xy 0.2794 0.9906)
			)
			(stroke
				(width 0)
				(type default)
			)
			(fill no)
			(layer "B.CrtYd")
		)
		(fp_line
			(start 0.2794 -0.1016)
			(end 0.2794 0.9906)
			(stroke
				(width 0.1)
				(type default)
			)
			(layer "B.Fab")
		)
		(fp_line
			(start -0.2794 -0.1016)
			(end 0.2794 -0.1016)
			(stroke
				(width 0.1)
				(type default)
			)
			(layer "B.Fab")
		)
		(fp_line
			(start 0.2794 0.9906)
			(end -0.2794 0.9906)
			(stroke
				(width 0.1)
				(type default)
			)
			(layer "B.Fab")
		)
		(fp_line
			(start -0.2794 0.9906)
			(end -0.2794 -0.1016)
			(stroke
				(width 0.1)
				(type default)
			)
			(layer "B.Fab")
		)
		(pad "1" smd rect
			(at 0 0 270)
			(size 0.508 0.508)
			(layers "B.Cu" "B.Mask" "B.Paste")
			(net "CLK_100M_CPU1_BCLK2_DN")
		)
		(pad "2" smd rect
			(at 0 0.889 270)
			(size 0.508 0.508)
			(layers "B.Cu" "B.Mask" "B.Paste")
			(net "GND")
		)
		(zone
			(layer "B.Cu")
			(hatch none 0.5)
			(connect_pads
				(clearance 0)
			)
			(min_thickness 0.25)
			(keepout
				(tracks allowed)
				(vias not_allowed)
				(pads allowed)
				(copperpour not_allowed)
				(footprints allowed)
			)
			(placement
				(enabled no)
				(sheetname "")
			)
			(fill
				(thermal_gap 0.5)
				(thermal_bridge_width 0.5)
				(island_removal_mode 0)
			)
			(polygon
				(pts
					(xy 163.16706 -84.582) (xy 163.16706 -84.074) (xy 163.54806 -84.074) (xy 163.54806 -84.582)
				)
			)
		)
		(zone
			(layer "B.Cu")
			(hatch none 0.5)
			(connect_pads
				(clearance 0)
			)
			(min_thickness 0.25)
			(keepout
				(tracks not_allowed)
				(vias allowed)
				(pads allowed)
				(copperpour not_allowed)
				(footprints allowed)
			)
			(placement
				(enabled no)
				(sheetname "")
			)
			(fill
				(thermal_gap 0.5)
				(thermal_bridge_width 0.5)
				(island_removal_mode 0)
			)
			(polygon
				(pts
					(xy 163.54806 -84.582) (xy 163.54806 -84.074) (xy 163.16706 -84.074) (xy 163.16706 -84.582)
				)
			)
		)
	)
	(footprint ""
		(layer "B.Cu")
		(at 350.024192 -77.834236)
		(property "Reference" "C3P26"
			(at 0 0 0)
			(layer "B.SilkS")
			(hide yes)
			(effects
				(font
					(size 1.27 1.27)
				)
				(justify mirror)
			)
		)
		(property "Value" ""
			(at 0 0 0)
			(layer "B.Fab")
			(effects
				(font
					(size 1.27 1.27)
				)
				(justify mirror)
			)
		)
		(duplicate_pad_numbers_are_jumpers no)
		(fp_poly
			(pts
				(xy -0.3048 -0.1016) (xy -0.3048 0.9906) (xy 0.3048 0.9906) (xy 0.3048 -0.1016)
			)
			(stroke
				(width 0)
				(type default)
			)
			(fill no)
			(layer "B.CrtYd")
		)
		(fp_line
			(start -0.3048 -0.1016)
			(end 0.3048 -0.1016)
			(stroke
				(width 0.1)
				(type default)
			)
			(layer "B.Fab")
		)
		(fp_line
			(start -0.3048 0.9906)
			(end -0.3048 -0.1016)
			(stroke
				(width 0.1)
				(type default)
			)
			(layer "B.Fab")
		)
		(fp_line
			(start 0.3048 -0.1016)
			(end 0.3048 0.9906)
			(stroke
				(width 0.1)
				(type default)
			)
			(layer "B.Fab")
		)
		(fp_line
			(start 0.3048 0.9906)
			(end -0.3048 0.9906)
			(stroke
				(width 0.1)
				(type default)
			)
			(layer "B.Fab")
		)
		(pad "1" smd rect
			(at 0 0 180)
			(size 0.508 0.508)
			(layers "B.Cu" "B.Mask" "B.Paste")
			(net "P3E_CPU0_PE1_SS_TXP<4>")
		)
		(pad "2" smd rect
			(at 0 0.889 180)
			(size 0.508 0.508)
			(layers "B.Cu" "B.Mask" "B.Paste")
			(net "P3E_CPU0_PE1_SS_C_TXP<4>")
		)
		(zone
			(layer "B.Cu")
			(hatch none 0.5)
			(connect_pads
				(clearance 0)
			)
			(min_thickness 0.25)
			(keepout
				(tracks allowed)
				(vias not_allowed)
				(pads allowed)
				(copperpour not_allowed)
				(footprints allowed)
			)
			(placement
				(enabled no)
				(sheetname "")
			)
			(fill
				(thermal_gap 0.5)
				(thermal_bridge_width 0.5)
				(island_removal_mode 0)
			)
			(polygon
				(pts
					(xy 350.278192 -77.580236) (xy 349.770192 -77.580236) (xy 349.770192 -77.199236) (xy 350.278192 -77.199236)
				)
			)
		)
		(zone
			(layer "B.Cu")
			(hatch none 0.5)
			(connect_pads
				(clearance 0)
			)
			(min_thickness 0.25)
			(keepout
				(tracks not_allowed)
				(vias allowed)
				(pads allowed)
				(copperpour not_allowed)
				(footprints allowed)
			)
			(placement
				(enabled no)
				(sheetname "")
			)
			(fill
				(thermal_gap 0.5)
				(thermal_bridge_width 0.5)
				(island_removal_mode 0)
			)
			(polygon
				(pts
					(xy 350.278192 -77.199236) (xy 349.770192 -77.199236) (xy 349.770192 -77.580236) (xy 350.278192 -77.580236)
				)
			)
		)
	)
)
